# S9S_MB_2U (Grand Teton) — schematic netlist excerpt (pin names and nets, part order shuffled) for the footprints in the layout excerpt that follows; sources: Cadence DE-HDL packaged netlist, KiCad conversion of 03242023_DA0F0TMBIJ0_F0T_Motherboard_J_brd_V01_OCP.brd

PC2226  Q_CAP  0.068UF 16V 10% X7R  pkg 0402  page 303 : A = HSC_SS ; B = AGND_HSC
R2724  Q_RES  0 5% EMPTY  pkg 0402LF  page 234 : A = SMB_BMC_SWB_R_SDA ; B = SMB_BMC_SWB_BUF_R_SDA
PC1248  Q_CAP  22UF 16V 20% X6S  pkg C0805  page 281 : A = SW_P12V_PVCCIN_CPU0_FLT ; B = GND

(kicad_pcb
	(version 20260206)
	(generator "pcbnew")
	(generator_version "10.0")
	(general
		(thickness 1.6)
		(legacy_teardrops no)
	)
	(paper "A4")
	(title_block
		(title "03242023_DA0F0TMBIJ0_F0T_Motherboard_J_brd_V01_OCP.brd")
		(comment 1 "Grand Teton / footprints 3110-3112 of 6105")
	)
	(layers
		(0 "F.Cu" signal "TOP")
		(4 "In1.Cu" signal "GND")
		(6 "In2.Cu" signal "IN1")
		(8 "In3.Cu" signal "GND1")
		(10 "In4.Cu" signal "IN2")
		(12 "In5.Cu" signal "GND2")
		(14 "In6.Cu" signal "IN3")
		(16 "In7.Cu" signal "GND3")
		(18 "In8.Cu" signal "VCC")
		(20 "In9.Cu" signal "VCC1")
		(22 "In10.Cu" signal "GND4")
		(24 "In11.Cu" signal "IN4")
		(26 "In12.Cu" signal "GND5")
		(28 "In13.Cu" signal "IN5")
		(30 "In14.Cu" signal "GND6")
		(32 "In15.Cu" signal "IN6")
		(34 "In16.Cu" signal "GND7")
		(2 "B.Cu" signal "BOTTOM")
		(9 "F.Adhes" user "F.Adhesive")
		(11 "B.Adhes" user "B.Adhesive")
		(13 "F.Paste" user "Package Geometry/Pastemask Top")
		(15 "B.Paste" user "Package Geometry/Pastemask Bottom")
		(5 "F.SilkS" user "Ref Des/Silkscreen Top")
		(7 "B.SilkS" user "Ref Des/Silkscreen Bottom")
		(1 "F.Mask" user "Board Geometry/Soldermask Top")
		(3 "B.Mask" user "Board Geometry/Soldermask Bottom")
		(17 "Dwgs.User" user "User.Drawings")
		(19 "Cmts.User" user "User.Comments")
		(21 "Eco1.User" user "User.Eco1")
		(23 "Eco2.User" user "User.Eco2")
		(25 "Edge.Cuts" user "Board Geometry/Outline")
		(27 "Margin" user)
		(31 "F.CrtYd" user "Package Geometry/Place Bound Top")
		(29 "B.CrtYd" user "Package Geometry/Place Bound Bottom")
		(35 "F.Fab" user "Ref Des/Assembly Top")
		(33 "B.Fab" user "Ref Des/Assembly Bottom")
	)
	(footprint ""
		(layer "F.Cu")
		(at 216.065608 -405.839422 180)
		(property "Reference" "PC2226"
			(at 0 0 180)
			(layer "F.SilkS")
			(hide yes)
			(effects
				(font
					(size 1.27 1.27)
				)
			)
		)
		(property "Value" ""
			(at 0 0 180)
			(layer "F.Fab")
			(effects
				(font
					(size 1.27 1.27)
				)
			)
		)
		(duplicate_pad_numbers_are_jumpers no)
		(fp_line
			(start 0.7874 0.4064)
			(end -0.7874 0.4064)
			(stroke
				(width 0.1524)
				(type default)
			)
			(layer "F.SilkS")
		)
		(fp_line
			(start 0.7874 -0.4064)
			(end 0.7874 0.4064)
			(stroke
				(width 0.1524)
				(type default)
			)
			(layer "F.SilkS")
		)
		(fp_line
			(start -0.7874 0.4064)
			(end -0.7874 -0.4064)
			(stroke
				(width 0.1524)
				(type default)
			)
			(layer "F.SilkS")
		)
		(fp_line
			(start -0.7874 -0.4064)
			(end 0.7874 -0.4064)
			(stroke
				(width 0.1524)
				(type default)
			)
			(layer "F.SilkS")
		)
		(fp_line
			(start 0.67945 0.3048)
			(end 0.120396 0.3048)
			(stroke
				(width 0.1)
				(type default)
			)
			(layer "F.Fab")
		)
		(fp_line
			(start 0.67945 -0.3048)
			(end 0.67945 0.3048)
			(stroke
				(width 0.1)
				(type default)
			)
			(layer "F.Fab")
		)
		(fp_line
			(start 0.12065 -0.2794)
			(end 0.12065 -0.3048)
			(stroke
				(width 0.1)
				(type default)
			)
			(layer "F.Fab")
		)
		(fp_line
			(start 0.12065 -0.3048)
			(end 0.67945 -0.3048)
			(stroke
				(width 0.1)
				(type default)
			)
			(layer "F.Fab")
		)
		(fp_line
			(start 0.120396 0.3048)
			(end 0.120396 0.2794)
			(stroke
				(width 0.1)
				(type default)
			)
			(layer "F.Fab")
		)
		(fp_line
			(start 0.120396 0.2794)
			(end -0.12065 0.2794)
			(stroke
				(width 0.1)
				(type default)
			)
			(layer "F.Fab")
		)
		(fp_line
			(start -0.12065 0.3048)
			(end -0.67945 0.3048)
			(stroke
				(width 0.1)
				(type default)
			)
			(layer "F.Fab")
		)
		(fp_line
			(start -0.12065 0.2794)
			(end -0.12065 0.3048)
			(stroke
				(width 0.1)
				(type default)
			)
			(layer "F.Fab")
		)
		(fp_line
			(start -0.12065 -0.2794)
			(end 0.12065 -0.2794)
			(stroke
				(width 0.1)
				(type default)
			)
			(layer "F.Fab")
		)
		(fp_line
			(start -0.12065 -0.305054)
			(end -0.12065 -0.2794)
			(stroke
				(width 0.1)
				(type default)
			)
			(layer "F.Fab")
		)
		(fp_line
			(start -0.67945 0.3048)
			(end -0.67945 -0.305054)
			(stroke
				(width 0.1)
				(type default)
			)
			(layer "F.Fab")
		)
		(fp_line
			(start -0.67945 -0.305054)
			(end -0.12065 -0.305054)
			(stroke
				(width 0.1)
				(type default)
			)
			(layer "F.Fab")
		)
		(pad "1" smd circle
			(at -0.40005 0 180)
			(size 0 0)
			(layers "F.Cu" "F.Mask" "F.Paste")
			(net "HSC_SS")
		)
		(pad "2" smd circle
			(at 0.40005 0 180)
			(size 0 0)
			(layers "F.Cu" "F.Mask" "F.Paste")
			(net "AGND_HSC")
		)
	)
	(footprint ""
		(layer "F.Cu")
		(at 374.325642 -350.780858)
		(property "Reference" "PC1248"
			(at 0 0 0)
			(layer "F.SilkS")
			(hide yes)
			(effects
				(font
					(size 1.27 1.27)
				)
			)
		)
		(property "Value" ""
			(at 0 0 0)
			(layer "F.Fab")
			(effects
				(font
					(size 1.27 1.27)
				)
			)
		)
		(duplicate_pad_numbers_are_jumpers no)
		(fp_line
			(start -1.524 -0.762)
			(end 1.524 -0.762)
			(stroke
				(width 0.1524)
				(type default)
			)
			(layer "F.SilkS")
		)
		(fp_line
			(start -1.524 0.762)
			(end -1.524 -0.762)
			(stroke
				(width 0.1524)
				(type default)
			)
			(layer "F.SilkS")
		)
		(fp_line
			(start 1.524 -0.762)
			(end 1.524 0.762)
			(stroke
				(width 0.1524)
				(type default)
			)
			(layer "F.SilkS")
		)
		(fp_line
			(start 1.524 0.762)
			(end -1.524 0.762)
			(stroke
				(width 0.1524)
				(type default)
			)
			(layer "F.SilkS")
		)
		(fp_line
			(start -1.1049 -0.724916)
			(end -1.1049 0.724916)
			(stroke
				(width 0.1)
				(type default)
			)
			(layer "F.Fab")
		)
		(fp_line
			(start -1.1049 0.724916)
			(end 1.1049 0.724916)
			(stroke
				(width 0.1)
				(type default)
			)
			(layer "F.Fab")
		)
		(fp_line
			(start 1.1049 -0.724916)
			(end -1.1049 -0.724916)
			(stroke
				(width 0.1)
				(type default)
			)
			(layer "F.Fab")
		)
		(fp_line
			(start 1.1049 0.724916)
			(end 1.1049 -0.724916)
			(stroke
				(width 0.1)
				(type default)
			)
			(layer "F.Fab")
		)
		(pad "1" smd rect
			(at -0.889 0 180)
			(size 1.016 1.27)
			(layers "F.Cu" "F.Mask" "F.Paste")
			(net "SW_P12V_PVCCIN_CPU0_FLT")
		)
		(pad "2" smd rect
			(at 0.889 0 180)
			(size 1.016 1.27)
			(layers "F.Cu" "F.Mask" "F.Paste")
			(net "GND")
		)
	)
	(footprint ""
		(layer "F.Cu")
		(at 163.88715 -419.911276)
		(property "Reference" "R2724"
			(at 0 0 0)
			(layer "F.SilkS")
			(hide yes)
			(effects
				(font
					(size 1.27 1.27)
				)
			)
		)
		(property "Value" ""
			(at 0 0 0)
			(layer "F.Fab")
			(effects
				(font
					(size 1.27 1.27)
				)
			)
		)
		(duplicate_pad_numbers_are_jumpers no)
		(fp_line
			(start -0.7874 -0.4064)
			(end 0.7874 -0.4064)
			(stroke
				(width 0.1524)
				(type default)
			)
			(layer "F.SilkS")
		)
		(fp_line
			(start -0.7874 0.4064)
			(end -0.7874 -0.4064)
			(stroke
				(width 0.1524)
				(type default)
			)
			(layer "F.SilkS")
		)
		(fp_line
			(start 0.7874 -0.4064)
			(end 0.7874 0.4064)
			(stroke
				(width 0.1524)
				(type default)
			)
			(layer "F.SilkS")
		)
		(fp_line
			(start 0.7874 0.4064)
			(end -0.7874 0.4064)
			(stroke
				(width 0.1524)
				(type default)
			)
			(layer "F.SilkS")
		)
		(fp_line
			(start -0.67945 -0.305054)
			(end -0.12065 -0.305054)
			(stroke
				(width 0.1)
				(type default)
			)
			(layer "F.Fab")
		)
		(fp_line
			(start -0.67945 0.3048)
			(end -0.67945 -0.305054)
			(stroke
				(width 0.1)
				(type default)
			)
			(layer "F.Fab")
		)
		(fp_line
			(start -0.12065 -0.305054)
			(end -0.12065 -0.2794)
			(stroke
				(width 0.1)
				(type default)
			)
			(layer "F.Fab")
		)
		(fp_line
			(start -0.12065 -0.2794)
			(end 0.12065 -0.2794)
			(stroke
				(width 0.1)
				(type default)
			)
			(layer "F.Fab")
		)
		(fp_line
			(start -0.12065 0.2794)
			(end -0.12065 0.3048)
			(stroke
				(width 0.1)
				(type default)
			)
			(layer "F.Fab")
		)
		(fp_line
			(start -0.12065 0.3048)
			(end -0.67945 0.3048)
			(stroke
				(width 0.1)
				(type default)
			)
			(layer "F.Fab")
		)
		(fp_line
			(start 0.120396 0.2794)
			(end -0.12065 0.2794)
			(stroke
				(width 0.1)
				(type default)
			)
			(layer "F.Fab")
		)
		(fp_line
			(start 0.120396 0.3048)
			(end 0.120396 0.2794)
			(stroke
				(width 0.1)
				(type default)
			)
			(layer "F.Fab")
		)
		(fp_line
			(start 0.12065 -0.3048)
			(end 0.67945 -0.3048)
			(stroke
				(width 0.1)
				(type default)
			)
			(layer "F.Fab")
		)
		(fp_line
			(start 0.12065 -0.2794)
			(end 0.12065 -0.3048)
			(stroke
				(width 0.1)
				(type default)
			)
			(layer "F.Fab")
		)
		(fp_line
			(start 0.67945 -0.3048)
			(end 0.67945 0.3048)
			(stroke
				(width 0.1)
				(type default)
			)
			(layer "F.Fab")
		)
		(fp_line
			(start 0.67945 0.3048)
			(end 0.120396 0.3048)
			(stroke
				(width 0.1)
				(type default)
			)
			(layer "F.Fab")
		)
		(pad "1" smd circle
			(at -0.40005 0)
			(size 0 0)
			(layers "F.Cu" "F.Mask" "F.Paste")
			(net "SMB_BMC_SWB_R_SDA")
		)
		(pad "2" smd circle
			(at 0.40005 0)
			(size 0 0)
			(layers "F.Cu" "F.Mask" "F.Paste")
			(net "SMB_BMC_SWB_BUF_R_SDA")
		)
	)
)
